(kicad_pcb
	(version 20241229)
	(generator "pcbnew")
	(generator_version "9.0")
	(general
		(thickness 1.294)
		(legacy_teardrops no)
	)
	(paper "A3")
	(title_block
		(title "Kintex 410T devboard")
		(date "2024-04-03")
		(rev "1.1.2")
		(comment 9 "footprints 6-11 of 975")
	)
	(layers
		(0 "F.Cu" mixed)
		(4 "In1.Cu" power)
		(6 "In2.Cu" power)
		(8 "In3.Cu" mixed)
		(10 "In4.Cu" power)
		(12 "In5.Cu" mixed)
		(14 "In6.Cu" power)
		(16 "In7.Cu" mixed)
		(18 "In8.Cu" power)
		(2 "B.Cu" mixed)
		(9 "F.Adhes" user "F.Adhesive")
		(11 "B.Adhes" user "B.Adhesive")
		(13 "F.Paste" user)
		(15 "B.Paste" user)
		(5 "F.SilkS" user "F.Silkscreen")
		(7 "B.SilkS" user "B.Silkscreen")
		(1 "F.Mask" user)
		(3 "B.Mask" user)
		(17 "Dwgs.User" user "User.Drawings")
		(19 "Cmts.User" user "User.Comments")
		(21 "Eco1.User" user "User.Eco1")
		(23 "Eco2.User" user "User.Eco2")
		(25 "Edge.Cuts" user)
		(27 "Margin" user)
		(31 "F.CrtYd" user "F.Courtyard")
		(29 "B.CrtYd" user "B.Courtyard")
		(35 "F.Fab" user)
		(33 "B.Fab" user)
	)
	(footprint "antmicro-footprints:Vishay_PowerPAK_1212-8_Single"
		(layer "F.Cu")
		(at 190.225 187.699)
		(descr "PowerPAK 1212-8 Single")
		(tags "Vishay PowerPAK 1212-8 Single")
		(property "Reference" "Q5"
			(at 2.925 1.851 90)
			(layer "F.SilkS")
			(effects
				(font
					(size 0.7 0.7)
					(thickness 0.15)
				)
				(justify left bottom)
			)
		)
		(property "Value" "SI7613DN-T1-GE3"
			(at -8 2.7 0)
			(layer "F.Fab")
			(effects
				(font
					(size 0.7 0.7)
					(thickness 0.15)
				)
				(justify left bottom)
			)
		)
		(property "Description" "Power MOSFET, P Channel, 20 V, 35 A, 0.0072 ohm, PowerPAK 1212, Surface Mount"
			(at 0 0 0)
			(layer "F.Fab")
			(hide yes)
			(effects
				(font
					(size 1.27 1.27)
					(thickness 0.15)
				)
			)
		)
		(property "Author" "Antmicro"
			(at 0 0 0)
			(layer "F.Fab")
			(hide yes)
			(effects
				(font
					(size 1 1)
					(thickness 0.15)
				)
			)
		)
		(property "License" "Apache-2.0"
			(at 0 0 0)
			(layer "F.Fab")
			(hide yes)
			(effects
				(font
					(size 1 1)
					(thickness 0.15)
				)
			)
		)
		(property "MPN" "SI7613DN-T1-GE3"
			(at 0 0 0)
			(layer "F.Fab")
			(hide yes)
			(effects
				(font
					(size 1 1)
					(thickness 0.15)
				)
			)
		)
		(property "Manufacturer" "Vishay"
			(at 0 0 0)
			(layer "F.Fab")
			(hide yes)
			(effects
				(font
					(size 1 1)
					(thickness 0.15)
				)
			)
		)
		(sheetname "Power supply")
		(sheetfile "power-supply.kicad_sch")
		(attr smd)
		(fp_line
			(start -1.651 -1.651)
			(end -1.651 -1.317)
			(stroke
				(width 0.15)
				(type solid)
			)
			(layer "F.SilkS")
		)
		(fp_line
			(start -1.651 -1.651)
			(end 1.648 -1.651)
			(stroke
				(width 0.15)
				(type solid)
			)
			(layer "F.SilkS")
		)
		(fp_line
			(start -1.635 1.3)
			(end -1.635 1.634)
			(stroke
				(width 0.15)
				(type solid)
			)
			(layer "F.SilkS")
		)
		(fp_line
			(start -1.635 1.634)
			(end 1.634 1.634)
			(stroke
				(width 0.15)
				(type solid)
			)
			(layer "F.SilkS")
		)
		(fp_line
			(start 1.634 1.3)
			(end 1.634 1.634)
			(stroke
				(width 0.15)
				(type solid)
			)
			(layer "F.SilkS")
		)
		(fp_line
			(start 1.648 -1.651)
			(end 1.648 -1.317)
			(stroke
				(width 0.15)
				(type solid)
			)
			(layer "F.SilkS")
		)
		(fp_circle
			(center -1.9 -1.4)
			(end -1.85 -1.4)
			(stroke
				(width 0.15)
				(type solid)
			)
			(fill yes)
			(layer "F.SilkS")
		)
		(fp_rect
			(start -2 -1.8)
			(end 2 1.798)
			(stroke
				(width 0.05)
				(type solid)
			)
			(fill no)
			(layer "F.CrtYd")
		)
		(fp_line
			(start -1.6425 -1.4175)
			(end -1.4175 -1.6425)
			(stroke
				(width 0.15)
				(type solid)
			)
			(layer "F.Fab")
		)
		(fp_rect
			(start -1.651 -1.651)
			(end 1.648 1.648)
			(stroke
				(width 0.15)
				(type solid)
			)
			(fill no)
			(layer "F.Fab")
		)
		(pad "1" smd rect
			(at -1.436 -0.99)
			(size 0.99 0.405)
			(layers "F.Cu" "F.Mask" "F.Paste")
			(net 702 "VDC")
			(pinfunction "S")
			(pintype "passive")
		)
		(pad "2" smd rect
			(at -1.436 -0.332)
			(size 0.99 0.405)
			(layers "F.Cu" "F.Mask" "F.Paste")
			(net 702 "VDC")
			(pinfunction "S")
			(pintype "passive")
		)
		(pad "3" smd rect
			(at -1.436 0.33)
			(size 0.99 0.405)
			(layers "F.Cu" "F.Mask" "F.Paste")
			(net 702 "VDC")
			(pinfunction "S")
			(pintype "passive")
		)
		(pad "4" smd rect
			(at -1.436 0.988)
			(size 0.99 0.405)
			(layers "F.Cu" "F.Mask" "F.Paste")
			(net 338 "Net-(Q5-G)")
			(pinfunction "G")
			(pintype "passive")
		)
		(pad "5" smd custom
			(at 0.557 0)
			(size 1.725 2.235)
			(layers "F.Cu" "F.Mask" "F.Paste")
			(net 4 "/Power supply/DC_IN")
			(pinfunction "D")
			(pintype "passive")
			(zone_connect 2)
			(options
				(clearance outline)
				(anchor rect)
			)
			(primitives
				(gr_poly
					(pts
						(xy 0.8625 0.1275) (xy 0.8625 -0.1275) (xy 1.3725 -0.1275) (xy 1.3725 -0.5325) (xy 0.8625 -0.5325)
						(xy 0.8625 -0.7875) (xy 1.3725 -0.7875) (xy 1.3725 -1.195) (xy 0.6125 -1.195) (xy 0.6125 1.195)
						(xy 1.3725 1.195) (xy 1.3725 0.7875) (xy 0.8625 0.7875) (xy 0.8625 0.5325) (xy 1.3725 0.5325)
						(xy 1.3725 0.1275)
					)
					(width 0)
					(fill yes)
				)
			)
		)
	)
	(footprint "antmicro-footprints:C_0402_1005Metric"
		(layer "F.Cu")
		(at 154.2 157 180)
		(descr "Capacitor SMD 0402")
		(tags "capacitor SMD 0402")
		(property "Reference" "C399"
			(at -0.95 -1.4 0)
			(layer "F.SilkS")
			(effects
				(font
					(size 0.7 0.7)
					(thickness 0.15)
				)
				(justify right bottom)
			)
		)
		(property "Value" "C_100n_0402"
			(at 0 1.4 0)
			(layer "F.Fab")
			(effects
				(font
					(size 0.7 0.7)
					(thickness 0.15)
				)
				(justify right bottom)
			)
		)
		(property "Description" "SMD Multilayer Ceramic Capacitor, 0.1 µF, 50 V, 0402 [1005 Metric], ± 10%, X5R, GRM Series"
			(at 0 0 180)
			(layer "F.Fab")
			(hide yes)
			(effects
				(font
					(size 1.27 1.27)
					(thickness 0.15)
				)
			)
		)
		(property "Author" "Antmicro"
			(at 308.4 314 0)
			(layer "F.Fab")
			(hide yes)
			(effects
				(font
					(size 1 1)
					(thickness 0.15)
				)
			)
		)
		(property "Dielectric" "X5R"
			(at 308.4 314 0)
			(layer "F.Fab")
			(hide yes)
			(effects
				(font
					(size 1 1)
					(thickness 0.15)
				)
			)
		)
		(property "License" "Apache-2.0"
			(at 308.4 314 0)
			(layer "F.Fab")
			(hide yes)
			(effects
				(font
					(size 1 1)
					(thickness 0.15)
				)
			)
		)
		(property "MPN" "GRM155R61H104KE14D"
			(at 308.4 314 0)
			(layer "F.Fab")
			(hide yes)
			(effects
				(font
					(size 1 1)
					(thickness 0.15)
				)
			)
		)
		(property "Manufacturer" "Murata"
			(at 308.4 314 0)
			(layer "F.Fab")
			(hide yes)
			(effects
				(font
					(size 1 1)
					(thickness 0.15)
				)
			)
		)
		(property "Val" "100n"
			(at 308.4 314 0)
			(layer "F.Fab")
			(hide yes)
			(effects
				(font
					(size 1 1)
					(thickness 0.15)
				)
			)
		)
		(property "Voltage" "50V"
			(at 308.4 314 0)
			(layer "F.Fab")
			(hide yes)
			(effects
				(font
					(size 1 1)
					(thickness 0.15)
				)
			)
		)
		(sheetname "DC-DC Converters")
		(sheetfile "dc-dc.kicad_sch")
		(attr smd)
		(fp_rect
			(start -0.925 -0.47)
			(end 0.925 0.47)
			(stroke
				(width 0.05)
				(type default)
			)
			(fill no)
			(layer "F.CrtYd")
		)
		(fp_line
			(start 0.504 0.248)
			(end -0.494 0.248)
			(stroke
				(width 0.15)
				(type solid)
			)
			(layer "F.Fab")
		)
		(fp_line
			(start 0.504 -0.25)
			(end 0.504 0.248)
			(stroke
				(width 0.15)
				(type solid)
			)
			(layer "F.Fab")
		)
		(fp_line
			(start -0.494 0.248)
			(end -0.494 -0.25)
			(stroke
				(width 0.15)
				(type solid)
			)
			(layer "F.Fab")
		)
		(fp_line
			(start -0.494 -0.25)
			(end 0.504 -0.25)
			(stroke
				(width 0.15)
				(type solid)
			)
			(layer "F.Fab")
		)
		(pad "1" smd roundrect
			(at -0.48 0 180)
			(size 0.59 0.64)
			(layers "F.Cu" "F.Mask" "F.Paste")
			(roundrect_rratio 0.25)
			(net 1 "GND")
			(pintype "passive")
		)
		(pad "2" smd roundrect
			(at 0.48 0 180)
			(size 0.59 0.64)
			(layers "F.Cu" "F.Mask" "F.Paste")
			(roundrect_rratio 0.25)
			(net 24 "+3V3")
			(pintype "passive")
		)
	)
	(footprint "antmicro-footprints:R_0402_1005Metric"
		(layer "F.Cu")
		(at 228.517121 159.7)
		(descr "Resistor SMD 0402")
		(tags "resistor SMD 0402")
		(property "Reference" "R56"
			(at -1.067121 1.2 0)
			(layer "F.SilkS")
			(effects
				(font
					(size 0.7 0.7)
					(thickness 0.15)
				)
				(justify left bottom)
			)
		)
		(property "Value" "R_1k_0402"
			(at 0 1.4 0)
			(layer "F.Fab")
			(effects
				(font
					(size 0.7 0.7)
					(thickness 0.15)
				)
				(justify left bottom)
			)
		)
		(property "Description" "SMD Chip Resistor, 1 kohm, ± 1%, 63 mW, 0402 [1005 Metric], Thick Film, General Purpose"
			(at 0 0 0)
			(layer "F.Fab")
			(hide yes)
			(effects
				(font
					(size 1.27 1.27)
					(thickness 0.15)
				)
			)
		)
		(property "Author" "Antmicro"
			(at 0 0 0)
			(layer "F.Fab")
			(hide yes)
			(effects
				(font
					(size 1 1)
					(thickness 0.15)
				)
			)
		)
		(property "License" "Apache-2.0"
			(at 0 0 0)
			(layer "F.Fab")
			(hide yes)
			(effects
				(font
					(size 1 1)
					(thickness 0.15)
				)
			)
		)
		(property "MPN" "CR0402-FX-1001GLF"
			(at 0 0 0)
			(layer "F.Fab")
			(hide yes)
			(effects
				(font
					(size 1 1)
					(thickness 0.15)
				)
			)
		)
		(property "Manufacturer" "Bourns"
			(at 0 0 0)
			(layer "F.Fab")
			(hide yes)
			(effects
				(font
					(size 1 1)
					(thickness 0.15)
				)
			)
		)
		(property "Tolerance" "1%"
			(at 0 0 0)
			(layer "F.Fab")
			(hide yes)
			(effects
				(font
					(size 1 1)
					(thickness 0.15)
				)
			)
		)
		(property "Val" "1k"
			(at 0 0 0)
			(layer "F.Fab")
			(hide yes)
			(effects
				(font
					(size 1 1)
					(thickness 0.15)
				)
			)
		)
		(sheetname "Power supply")
		(sheetfile "power-supply.kicad_sch")
		(attr smd)
		(fp_rect
			(start -0.925 -0.47)
			(end 0.925 0.47)
			(stroke
				(width 0.05)
				(type default)
			)
			(fill no)
			(layer "F.CrtYd")
		)
		(fp_rect
			(start -0.5 -0.25)
			(end 0.5 0.25)
			(stroke
				(width 0.15)
				(type solid)
			)
			(fill no)
			(layer "F.Fab")
		)
		(pad "1" smd roundrect
			(at -0.48 0)
			(size 0.59 0.64)
			(layers "F.Cu" "F.Mask" "F.Paste")
			(roundrect_rratio 0.25)
			(net 700 "/Power supply/USB_PD_VBUS")
			(pintype "passive")
		)
		(pad "2" smd roundrect
			(at 0.48 0)
			(size 0.59 0.64)
			(layers "F.Cu" "F.Mask" "F.Paste")
			(roundrect_rratio 0.25)
			(net 888 "/Power supply/PDBUS_DISCH")
			(pintype "passive")
		)
	)
	(footprint "antmicro-footprints:R_0402_1005Metric"
		(layer "F.Cu")
		(at 259.6 128.5 180)
		(descr "Resistor SMD 0402")
		(tags "resistor SMD 0402")
		(property "Reference" "R361"
			(at 1.05 5.8 180)
			(layer "F.SilkS")
			(effects
				(font
					(size 0.7 0.7)
					(thickness 0.15)
				)
				(justify left bottom)
			)
		)
		(property "Value" "R_5k1_0402"
			(at 0 1.4 180)
			(layer "F.Fab")
			(effects
				(font
					(size 0.7 0.7)
					(thickness 0.15)
				)
				(justify left bottom)
			)
		)
		(property "Description" "SMD Chip Resistor, 5.1 kohm, ± 1%, 63 mW, 0402 [1005 Metric], Thick Film, General Purpose"
			(at 0 0 180)
			(layer "F.Fab")
			(hide yes)
			(effects
				(font
					(size 1.27 1.27)
					(thickness 0.15)
				)
			)
		)
		(property "Author" "Antmicro"
			(at 519.2 257 0)
			(layer "F.Fab")
			(hide yes)
			(effects
				(font
					(size 1 1)
					(thickness 0.15)
				)
			)
		)
		(property "License" "Apache-2.0"
			(at 519.2 257 0)
			(layer "F.Fab")
			(hide yes)
			(effects
				(font
					(size 1 1)
					(thickness 0.15)
				)
			)
		)
		(property "MPN" "CR0402-FX-5101GLF"
			(at 519.2 257 0)
			(layer "F.Fab")
			(hide yes)
			(effects
				(font
					(size 1 1)
					(thickness 0.15)
				)
			)
		)
		(property "Manufacturer" "Bourns"
			(at 519.2 257 0)
			(layer "F.Fab")
			(hide yes)
			(effects
				(font
					(size 1 1)
					(thickness 0.15)
				)
			)
		)
		(property "Tolerance" "1%"
			(at 519.2 257 0)
			(layer "F.Fab")
			(hide yes)
			(effects
				(font
					(size 1 1)
					(thickness 0.15)
				)
			)
		)
		(property "Val" "5k1"
			(at 519.2 257 0)
			(layer "F.Fab")
			(hide yes)
			(effects
				(font
					(size 1 1)
					(thickness 0.15)
				)
			)
		)
		(sheetname "USB PHY")
		(sheetfile "usb-phy.kicad_sch")
		(attr smd)
		(fp_rect
			(start -0.925 -0.47)
			(end 0.925 0.47)
			(stroke
				(width 0.05)
				(type default)
			)
			(fill no)
			(layer "F.CrtYd")
		)
		(fp_rect
			(start -0.5 -0.25)
			(end 0.5 0.25)
			(stroke
				(width 0.15)
				(type solid)
			)
			(fill no)
			(layer "F.Fab")
		)
		(pad "1" smd roundrect
			(at -0.48 0 180)
			(size 0.59 0.64)
			(layers "F.Cu" "F.Mask" "F.Paste")
			(roundrect_rratio 0.25)
			(net 841 "/USB PHY/USB_USR_CC1")
			(pintype "passive")
		)
		(pad "2" smd roundrect
			(at 0.48 0 180)
			(size 0.59 0.64)
			(layers "F.Cu" "F.Mask" "F.Paste")
			(roundrect_rratio 0.25)
			(net 1 "GND")
			(pintype "passive")
		)
	)
	(footprint "antmicro-footprints:R_0402_1005Metric"
		(layer "F.Cu")
		(at 159.7 147.9 180)
		(descr "Resistor SMD 0402")
		(tags "resistor SMD 0402")
		(property "Reference" "R329"
			(at 0.9 -1.25 180)
			(layer "F.SilkS")
			(effects
				(font
					(size 0.7 0.7)
					(thickness 0.15)
				)
				(justify left bottom)
			)
		)
		(property "Value" "R_0R_0402"
			(at 0 1.4 180)
			(layer "F.Fab")
			(effects
				(font
					(size 0.7 0.7)
					(thickness 0.15)
				)
				(justify left bottom)
			)
		)
		(property "Description" "SMD Chip Resistor, Jumper, 0 ohm, 100 mW, 0402 [1005 Metric], Thick Film, General Purpose"
			(at 0 0 180)
			(layer "F.Fab")
			(hide yes)
			(effects
				(font
					(size 1.27 1.27)
					(thickness 0.15)
				)
			)
		)
		(property "Author" "Antmicro"
			(at 319.4 295.8 0)
			(layer "F.Fab")
			(hide yes)
			(effects
				(font
					(size 1 1)
					(thickness 0.15)
				)
			)
		)
		(property "Current" "1A"
			(at 319.4 295.8 0)
			(layer "F.Fab")
			(hide yes)
			(effects
				(font
					(size 1 1)
					(thickness 0.15)
				)
			)
		)
		(property "License" "Apache-2.0"
			(at 319.4 295.8 0)
			(layer "F.Fab")
			(hide yes)
			(effects
				(font
					(size 1 1)
					(thickness 0.15)
				)
			)
		)
		(property "MPN" "ERJ2GE0R00X"
			(at 319.4 295.8 0)
			(layer "F.Fab")
			(hide yes)
			(effects
				(font
					(size 1 1)
					(thickness 0.15)
				)
			)
		)
		(property "Manufacturer" "Panasonic"
			(at 319.4 295.8 0)
			(layer "F.Fab")
			(hide yes)
			(effects
				(font
					(size 1 1)
					(thickness 0.15)
				)
			)
		)
		(property "Tolerance" ""
			(at 319.4 295.8 0)
			(layer "F.Fab")
			(hide yes)
			(effects
				(font
					(size 1 1)
					(thickness 0.15)
				)
			)
		)
		(property "Val" "0R"
			(at 319.4 295.8 0)
			(layer "F.Fab")
			(hide yes)
			(effects
				(font
					(size 1 1)
					(thickness 0.15)
				)
			)
		)
		(sheetname "DC-DC Converters")
		(sheetfile "dc-dc.kicad_sch")
		(attr smd)
		(fp_rect
			(start -0.925 -0.47)
			(end 0.925 0.47)
			(stroke
				(width 0.05)
				(type default)
			)
			(fill no)
			(layer "F.CrtYd")
		)
		(fp_rect
			(start -0.5 -0.25)
			(end 0.5 0.25)
			(stroke
				(width 0.15)
				(type solid)
			)
			(fill no)
			(layer "F.Fab")
		)
		(pad "1" smd roundrect
			(at -0.48 0 180)
			(size 0.59 0.64)
			(layers "F.Cu" "F.Mask" "F.Paste")
			(roundrect_rratio 0.25)
			(net 869 "Net-(NT1-Pad1)")
			(pintype "passive")
		)
		(pad "2" smd roundrect
			(at 0.48 0 180)
			(size 0.59 0.64)
			(layers "F.Cu" "F.Mask" "F.Paste")
			(roundrect_rratio 0.25)
			(net 15 "Net-(U41-OUT)")
			(pintype "passive")
		)
	)
	(footprint "antmicro-footprints:C_0402_1005Metric"
		(layer "F.Cu")
		(at 235.925 116.525 180)
		(descr "Capacitor SMD 0402")
		(tags "capacitor SMD 0402")
		(property "Reference" "C209"
			(at -3.575 -0.325 180)
			(layer "F.SilkS")
			(effects
				(font
					(size 0.7 0.7)
					(thickness 0.15)
				)
				(justify right bottom)
			)
		)
		(property "Value" "C_100n_0402"
			(at 0 1.4 0)
			(layer "F.Fab")
			(effects
				(font
					(size 0.7 0.7)
					(thickness 0.15)
				)
				(justify right bottom)
			)
		)
		(property "Description" "SMD Multilayer Ceramic Capacitor, 0.1 µF, 50 V, 0402 [1005 Metric], ± 10%, X5R, GRM Series"
			(at 0 0 180)
			(layer "F.Fab")
			(hide yes)
			(effects
				(font
					(size 1.27 1.27)
					(thickness 0.15)
				)
			)
		)
		(property "Author" "Antmicro"
			(at 471.85 233.05 0)
			(layer "F.Fab")
			(hide yes)
			(effects
				(font
					(size 1 1)
					(thickness 0.15)
				)
			)
		)
		(property "Dielectric" "X5R"
			(at 471.85 233.05 0)
			(layer "F.Fab")
			(hide yes)
			(effects
				(font
					(size 1 1)
					(thickness 0.15)
				)
			)
		)
		(property "License" "Apache-2.0"
			(at 471.85 233.05 0)
			(layer "F.Fab")
			(hide yes)
			(effects
				(font
					(size 1 1)
					(thickness 0.15)
				)
			)
		)
		(property "MPN" "GRM155R61H104KE14D"
			(at 471.85 233.05 0)
			(layer "F.Fab")
			(hide yes)
			(effects
				(font
					(size 1 1)
					(thickness 0.15)
				)
			)
		)
		(property "Manufacturer" "Murata"
			(at 471.85 233.05 0)
			(layer "F.Fab")
			(hide yes)
			(effects
				(font
					(size 1 1)
					(thickness 0.15)
				)
			)
		)
		(property "Val" "100n"
			(at 471.85 233.05 0)
			(layer "F.Fab")
			(hide yes)
			(effects
				(font
					(size 1 1)
					(thickness 0.15)
				)
			)
		)
		(property "Voltage" "50V"
			(at 471.85 233.05 0)
			(layer "F.Fab")
			(hide yes)
			(effects
				(font
					(size 1 1)
					(thickness 0.15)
				)
			)
		)
		(sheetname "SPI Flash + SD Card")
		(sheetfile "spi-flash.kicad_sch")
		(attr smd)
		(fp_rect
			(start -0.925 -0.47)
			(end 0.925 0.47)
			(stroke
				(width 0.05)
				(type default)
			)
			(fill no)
			(layer "F.CrtYd")
		)
		(fp_line
			(start 0.504 0.248)
			(end -0.494 0.248)
			(stroke
				(width 0.15)
				(type solid)
			)
			(layer "F.Fab")
		)
		(fp_line
			(start 0.504 -0.25)
			(end 0.504 0.248)
			(stroke
				(width 0.15)
				(type solid)
			)
			(layer "F.Fab")
		)
		(fp_line
			(start -0.494 0.248)
			(end -0.494 -0.25)
			(stroke
				(width 0.15)
				(type solid)
			)
			(layer "F.Fab")
		)
		(fp_line
			(start -0.494 -0.25)
			(end 0.504 -0.25)
			(stroke
				(width 0.15)
				(type solid)
			)
			(layer "F.Fab")
		)
		(pad "1" smd roundrect
			(at -0.48 0 180)
			(size 0.59 0.64)
			(layers "F.Cu" "F.Mask" "F.Paste")
			(roundrect_rratio 0.25)
			(net 1 "GND")
			(pintype "passive")
		)
		(pad "2" smd roundrect
			(at 0.48 0 180)
			(size 0.59 0.64)
			(layers "F.Cu" "F.Mask" "F.Paste")
			(roundrect_rratio 0.25)
			(net 24 "+3V3")
			(pintype "passive")
		)
	)
)
